(kicad_pcb
	(version 20260206)
	(generator "pcbnew")
	(generator_version "10.0")
	(general
		(thickness 1.6)
		(legacy_teardrops no)
	)
	(paper "A4")
	(title_block
		(title "v2-tray-backplane — ms_tbp_v2.brd")
		(comment 1 "Open CloudServer (Microsoft) / footprint 65 of 164 (J24), pads 1-84 of 84")
	)
	(layers
		(0 "F.Cu" signal "TOP")
		(4 "In1.Cu" signal "LYR2")
		(6 "In2.Cu" signal "LYR3")
		(8 "In3.Cu" signal "LYR4")
		(10 "In4.Cu" signal "LYR5")
		(12 "In5.Cu" signal "LYR6")
		(14 "In6.Cu" signal "LYR7")
		(2 "B.Cu" signal "BOTTOM")
		(9 "F.Adhes" user "F.Adhesive")
		(11 "B.Adhes" user "B.Adhesive")
		(13 "F.Paste" user "Package Geometry/Pastemask Top")
		(15 "B.Paste" user "Package Geometry/Pastemask Bottom")
		(5 "F.SilkS" user "Ref Des/Silkscreen Top")
		(7 "B.SilkS" user "Ref Des/Silkscreen Bottom")
		(1 "F.Mask" user "Board Geometry/Soldermask Top")
		(3 "B.Mask" user "Board Geometry/Soldermask Bottom")
		(17 "Dwgs.User" user "User.Drawings")
		(19 "Cmts.User" user "User.Comments")
		(21 "Eco1.User" user "User.Eco1")
		(23 "Eco2.User" user "User.Eco2")
		(25 "Edge.Cuts" user "Board Geometry/Outline")
		(27 "Margin" user)
		(31 "F.CrtYd" user "Package Geometry/Place Bound Top")
		(29 "B.CrtYd" user "Package Geometry/Place Bound Bottom")
		(35 "F.Fab" user "Ref Des/Assembly Top")
		(33 "B.Fab" user "Ref Des/Assembly Bottom")
	)
	(footprint ""
		(layer "F.Cu")
		(at -19.850001 13.639371 180)
		(property "Reference" "J24"
			(at 3.009999 -15.100729 0)
			(unlocked yes)
			(layer "F.SilkS")
			(effects
				(font
					(size 0.762 0.5334)
					(thickness 0.1016)
				)
			)
		)
		(property "Value" ""
			(at 0 0 180)
			(layer "F.Fab")
			(effects
				(font
					(size 1.27 1.27)
				)
			)
		)
		(duplicate_pad_numbers_are_jumpers no)
		(pad "" thru_hole circle
			(at 2.999999 4.399999 180)
			(size 3.81 3.81)
			(drill 2.2098)
			(layers "*.Cu" "*.Mask")
			(remove_unused_layers no)
		)
		(pad "" thru_hole circle
			(at 14 4.399999 180)
			(size 3.81 3.81)
			(drill 2.2098)
			(layers "*.Cu" "*.Mask")
			(remove_unused_layers no)
		)
		(pad "1" thru_hole circle
			(at 1.5 -13.109999 180)
			(size 1.1176 1.1176)
			(drill 0.6096)
			(layers "*.Cu" "*.Mask")
			(remove_unused_layers no)
			(net "GND")
		)
		(pad "1A1" thru_hole circle
			(at 0 0 180)
			(size 0.6858 0.6858)
			(drill 0.381)
			(layers "*.Cu" "*.Mask")
			(remove_unused_layers no)
			(net "Net_393")
		)
		(pad "1A2" thru_hole circle
			(at 0.750001 1.4 180)
			(size 0.6858 0.6858)
			(drill 0.381)
			(layers "*.Cu" "*.Mask")
			(remove_unused_layers no)
			(net "Net_392")
		)
		(pad "1A3" thru_hole circle
			(at 1.5 0.700001 180)
			(size 0.6858 0.6858)
			(drill 0.381)
			(layers "*.Cu" "*.Mask")
			(remove_unused_layers no)
			(net "GND")
		)
		(pad "1A4" thru_hole circle
			(at 2.250001 0 180)
			(size 0.6858 0.6858)
			(drill 0.381)
			(layers "*.Cu" "*.Mask")
			(remove_unused_layers no)
			(net "SAS_B2_RX2P")
		)
		(pad "1A5" thru_hole circle
			(at 2.999999 1.4 180)
			(size 0.6858 0.6858)
			(drill 0.381)
			(layers "*.Cu" "*.Mask")
			(remove_unused_layers no)
			(net "SAS_B2_RX2N")
		)
		(pad "1A6" thru_hole circle
			(at 3.75 0.700001 180)
			(size 0.6858 0.6858)
			(drill 0.381)
			(layers "*.Cu" "*.Mask")
			(remove_unused_layers no)
			(net "GND")
		)
		(pad "1A7" thru_hole circle
			(at 4.500001 0 180)
			(size 0.6858 0.6858)
			(drill 0.381)
			(layers "*.Cu" "*.Mask")
			(remove_unused_layers no)
			(net "SAS_B2_RX4P")
		)
		(pad "1A8" thru_hole circle
			(at 5.25 1.4 180)
			(size 0.6858 0.6858)
			(drill 0.381)
			(layers "*.Cu" "*.Mask")
			(remove_unused_layers no)
			(net "SAS_B2_RX4N")
		)
		(pad "1A9" thru_hole circle
			(at 6.000001 0.700001 180)
			(size 0.6858 0.6858)
			(drill 0.381)
			(layers "*.Cu" "*.Mask")
			(remove_unused_layers no)
			(net "GND")
		)
		(pad "1B1" thru_hole circle
			(at 0 -3.8 180)
			(size 0.6858 0.6858)
			(drill 0.381)
			(layers "*.Cu" "*.Mask")
			(remove_unused_layers no)
			(net "Net_391")
		)
		(pad "1B2" thru_hole circle
			(at 0.750001 -2.4 180)
			(size 0.6858 0.6858)
			(drill 0.381)
			(layers "*.Cu" "*.Mask")
			(remove_unused_layers no)
			(net "Net_390")
		)
		(pad "1B3" thru_hole circle
			(at 1.5 -3.099999 180)
			(size 0.6858 0.6858)
			(drill 0.381)
			(layers "*.Cu" "*.Mask")
			(remove_unused_layers no)
			(net "GND")
		)
		(pad "1B4" thru_hole circle
			(at 2.250001 -3.8 180)
			(size 0.6858 0.6858)
			(drill 0.381)
			(layers "*.Cu" "*.Mask")
			(remove_unused_layers no)
			(net "SAS_B2_RX1P")
		)
		(pad "1B5" thru_hole circle
			(at 2.999999 -2.4 180)
			(size 0.6858 0.6858)
			(drill 0.381)
			(layers "*.Cu" "*.Mask")
			(remove_unused_layers no)
			(net "SAS_B2_RX1N")
		)
		(pad "1B6" thru_hole circle
			(at 3.75 -3.099999 180)
			(size 0.6858 0.6858)
			(drill 0.381)
			(layers "*.Cu" "*.Mask")
			(remove_unused_layers no)
			(net "GND")
		)
		(pad "1B7" thru_hole circle
			(at 4.500001 -3.8 180)
			(size 0.6858 0.6858)
			(drill 0.381)
			(layers "*.Cu" "*.Mask")
			(remove_unused_layers no)
			(net "SAS_B2_RX3P")
		)
		(pad "1B8" thru_hole circle
			(at 5.25 -2.4 180)
			(size 0.6858 0.6858)
			(drill 0.381)
			(layers "*.Cu" "*.Mask")
			(remove_unused_layers no)
			(net "SAS_B2_RX3N")
		)
		(pad "1B9" thru_hole circle
			(at 6.000001 -3.099999 180)
			(size 0.6858 0.6858)
			(drill 0.381)
			(layers "*.Cu" "*.Mask")
			(remove_unused_layers no)
			(net "GND")
		)
		(pad "1C1" thru_hole circle
			(at 0 -7.6 180)
			(size 0.6858 0.6858)
			(drill 0.381)
			(layers "*.Cu" "*.Mask")
			(remove_unused_layers no)
			(net "Net_389")
		)
		(pad "1C2" thru_hole circle
			(at 0.750001 -6.2 180)
			(size 0.6858 0.6858)
			(drill 0.381)
			(layers "*.Cu" "*.Mask")
			(remove_unused_layers no)
			(net "Net_388")
		)
		(pad "1C3" thru_hole circle
			(at 1.5 -6.899999 180)
			(size 0.6858 0.6858)
			(drill 0.381)
			(layers "*.Cu" "*.Mask")
			(remove_unused_layers no)
			(net "GND")
		)
		(pad "1C4" thru_hole circle
			(at 2.250001 -7.6 180)
			(size 0.6858 0.6858)
			(drill 0.381)
			(layers "*.Cu" "*.Mask")
			(remove_unused_layers no)
			(net "SAS_B2_TX2P")
		)
		(pad "1C5" thru_hole circle
			(at 2.999999 -6.2 180)
			(size 0.6858 0.6858)
			(drill 0.381)
			(layers "*.Cu" "*.Mask")
			(remove_unused_layers no)
			(net "SAS_B2_TX2N")
		)
		(pad "1C6" thru_hole circle
			(at 3.75 -6.899999 180)
			(size 0.6858 0.6858)
			(drill 0.381)
			(layers "*.Cu" "*.Mask")
			(remove_unused_layers no)
			(net "GND")
		)
		(pad "1C7" thru_hole circle
			(at 4.500001 -7.6 180)
			(size 0.6858 0.6858)
			(drill 0.381)
			(layers "*.Cu" "*.Mask")
			(remove_unused_layers no)
			(net "SAS_B2_TX4P")
		)
		(pad "1C8" thru_hole circle
			(at 5.25 -6.2 180)
			(size 0.6858 0.6858)
			(drill 0.381)
			(layers "*.Cu" "*.Mask")
			(remove_unused_layers no)
			(net "SAS_B2_TX4N")
		)
		(pad "1C9" thru_hole circle
			(at 6.000001 -6.899999 180)
			(size 0.6858 0.6858)
			(drill 0.381)
			(layers "*.Cu" "*.Mask")
			(remove_unused_layers no)
			(net "GND")
		)
		(pad "1D1" thru_hole circle
			(at 0 -11.4 180)
			(size 0.6858 0.6858)
			(drill 0.381)
			(layers "*.Cu" "*.Mask")
			(remove_unused_layers no)
			(net "Net_387")
		)
		(pad "1D2" thru_hole circle
			(at 0.750001 -10 180)
			(size 0.6858 0.6858)
			(drill 0.381)
			(layers "*.Cu" "*.Mask")
			(remove_unused_layers no)
			(net "Net_386")
		)
		(pad "1D3" thru_hole circle
			(at 1.5 -10.699999 180)
			(size 0.6858 0.6858)
			(drill 0.381)
			(layers "*.Cu" "*.Mask")
			(remove_unused_layers no)
			(net "GND")
		)
		(pad "1D4" thru_hole circle
			(at 2.250001 -11.4 180)
			(size 0.6858 0.6858)
			(drill 0.381)
			(layers "*.Cu" "*.Mask")
			(remove_unused_layers no)
			(net "SAS_B2_TX1P")
		)
		(pad "1D5" thru_hole circle
			(at 2.999999 -10 180)
			(size 0.6858 0.6858)
			(drill 0.381)
			(layers "*.Cu" "*.Mask")
			(remove_unused_layers no)
			(net "SAS_B2_TX1N")
		)
		(pad "1D6" thru_hole circle
			(at 3.75 -10.699999 180)
			(size 0.6858 0.6858)
			(drill 0.381)
			(layers "*.Cu" "*.Mask")
			(remove_unused_layers no)
			(net "GND")
		)
		(pad "1D7" thru_hole circle
			(at 4.500001 -11.4 180)
			(size 0.6858 0.6858)
			(drill 0.381)
			(layers "*.Cu" "*.Mask")
			(remove_unused_layers no)
			(net "SAS_B2_TX3P")
		)
		(pad "1D8" thru_hole circle
			(at 5.25 -10 180)
			(size 0.6858 0.6858)
			(drill 0.381)
			(layers "*.Cu" "*.Mask")
			(remove_unused_layers no)
			(net "SAS_B2_TX3N")
		)
		(pad "1D9" thru_hole circle
			(at 6.000001 -10.699999 180)
			(size 0.6858 0.6858)
			(drill 0.381)
			(layers "*.Cu" "*.Mask")
			(remove_unused_layers no)
			(net "GND")
		)
		(pad "2" thru_hole circle
			(at 6.000001 -13.109999 180)
			(size 1.1176 1.1176)
			(drill 0.6096)
			(layers "*.Cu" "*.Mask")
			(remove_unused_layers no)
			(net "GND")
		)
		(pad "2A1" thru_hole circle
			(at 11.000001 0 180)
			(size 0.6858 0.6858)
			(drill 0.381)
			(layers "*.Cu" "*.Mask")
			(remove_unused_layers no)
			(net "Net_385")
		)
		(pad "2A2" thru_hole circle
			(at 11.749999 1.4 180)
			(size 0.6858 0.6858)
			(drill 0.381)
			(layers "*.Cu" "*.Mask")
			(remove_unused_layers no)
			(net "Net_384")
		)
		(pad "2A3" thru_hole circle
			(at 12.5 0.700001 180)
			(size 0.6858 0.6858)
			(drill 0.381)
			(layers "*.Cu" "*.Mask")
			(remove_unused_layers no)
			(net "GND")
		)
		(pad "2A4" thru_hole circle
			(at 13.249999 0 180)
			(size 0.6858 0.6858)
			(drill 0.381)
			(layers "*.Cu" "*.Mask")
			(remove_unused_layers no)
			(net "SAS_B2_RX6P")
		)
		(pad "2A5" thru_hole circle
			(at 14 1.4 180)
			(size 0.6858 0.6858)
			(drill 0.381)
			(layers "*.Cu" "*.Mask")
			(remove_unused_layers no)
			(net "SAS_B2_RX6N")
		)
		(pad "2A6" thru_hole circle
			(at 14.750001 0.700001 180)
			(size 0.6858 0.6858)
			(drill 0.381)
			(layers "*.Cu" "*.Mask")
			(remove_unused_layers no)
			(net "GND")
		)
		(pad "2A7" thru_hole circle
			(at 15.499999 0 180)
			(size 0.6858 0.6858)
			(drill 0.381)
			(layers "*.Cu" "*.Mask")
			(remove_unused_layers no)
			(net "SAS_B2_RX8P")
		)
		(pad "2A8" thru_hole circle
			(at 16.250001 1.4 180)
			(size 0.6858 0.6858)
			(drill 0.381)
			(layers "*.Cu" "*.Mask")
			(remove_unused_layers no)
			(net "SAS_B2_RX8N")
		)
		(pad "2A9" thru_hole circle
			(at 16.999999 0.700001 180)
			(size 0.6858 0.6858)
			(drill 0.381)
			(layers "*.Cu" "*.Mask")
			(remove_unused_layers no)
			(net "GND")
		)
		(pad "2B1" thru_hole circle
			(at 11.000001 -3.8 180)
			(size 0.6858 0.6858)
			(drill 0.381)
			(layers "*.Cu" "*.Mask")
			(remove_unused_layers no)
			(net "Net_383")
		)
		(pad "2B2" thru_hole circle
			(at 11.749999 -2.4 180)
			(size 0.6858 0.6858)
			(drill 0.381)
			(layers "*.Cu" "*.Mask")
			(remove_unused_layers no)
			(net "Net_382")
		)
		(pad "2B3" thru_hole circle
			(at 12.5 -3.099999 180)
			(size 0.6858 0.6858)
			(drill 0.381)
			(layers "*.Cu" "*.Mask")
			(remove_unused_layers no)
			(net "GND")
		)
		(pad "2B4" thru_hole circle
			(at 13.249999 -3.8 180)
			(size 0.6858 0.6858)
			(drill 0.381)
			(layers "*.Cu" "*.Mask")
			(remove_unused_layers no)
			(net "SAS_B2_RX5P")
		)
		(pad "2B5" thru_hole circle
			(at 14 -2.4 180)
			(size 0.6858 0.6858)
			(drill 0.381)
			(layers "*.Cu" "*.Mask")
			(remove_unused_layers no)
			(net "SAS_B2_RX5N")
		)
		(pad "2B6" thru_hole circle
			(at 14.750001 -3.099999 180)
			(size 0.6858 0.6858)
			(drill 0.381)
			(layers "*.Cu" "*.Mask")
			(remove_unused_layers no)
			(net "GND")
		)
		(pad "2B7" thru_hole circle
			(at 15.499999 -3.8 180)
			(size 0.6858 0.6858)
			(drill 0.381)
			(layers "*.Cu" "*.Mask")
			(remove_unused_layers no)
			(net "SAS_B2_RX7P")
		)
		(pad "2B8" thru_hole circle
			(at 16.250001 -2.4 180)
			(size 0.6858 0.6858)
			(drill 0.381)
			(layers "*.Cu" "*.Mask")
			(remove_unused_layers no)
			(net "SAS_B2_RX7N")
		)
		(pad "2B9" thru_hole circle
			(at 16.999999 -3.099999 180)
			(size 0.6858 0.6858)
			(drill 0.381)
			(layers "*.Cu" "*.Mask")
			(remove_unused_layers no)
			(net "GND")
		)
		(pad "2C1" thru_hole circle
			(at 11.000001 -7.6 180)
			(size 0.6858 0.6858)
			(drill 0.381)
			(layers "*.Cu" "*.Mask")
			(remove_unused_layers no)
			(net "Net_381")
		)
		(pad "2C2" thru_hole circle
			(at 11.749999 -6.2 180)
			(size 0.6858 0.6858)
			(drill 0.381)
			(layers "*.Cu" "*.Mask")
			(remove_unused_layers no)
			(net "Net_380")
		)
		(pad "2C3" thru_hole circle
			(at 12.5 -6.899999 180)
			(size 0.6858 0.6858)
			(drill 0.381)
			(layers "*.Cu" "*.Mask")
			(remove_unused_layers no)
			(net "GND")
		)
		(pad "2C4" thru_hole circle
			(at 13.249999 -7.6 180)
			(size 0.6858 0.6858)
			(drill 0.381)
			(layers "*.Cu" "*.Mask")
			(remove_unused_layers no)
			(net "SAS_B2_TX6P")
		)
		(pad "2C5" thru_hole circle
			(at 14 -6.2 180)
			(size 0.6858 0.6858)
			(drill 0.381)
			(layers "*.Cu" "*.Mask")
			(remove_unused_layers no)
			(net "SAS_B2_TX6N")
		)
		(pad "2C6" thru_hole circle
			(at 14.750001 -6.899999 180)
			(size 0.6858 0.6858)
			(drill 0.381)
			(layers "*.Cu" "*.Mask")
			(remove_unused_layers no)
			(net "GND")
		)
		(pad "2C7" thru_hole circle
			(at 15.499999 -7.6 180)
			(size 0.6858 0.6858)
			(drill 0.381)
			(layers "*.Cu" "*.Mask")
			(remove_unused_layers no)
			(net "SAS_B2_TX8P")
		)
		(pad "2C8" thru_hole circle
			(at 16.250001 -6.2 180)
			(size 0.6858 0.6858)
			(drill 0.381)
			(layers "*.Cu" "*.Mask")
			(remove_unused_layers no)
			(net "SAS_B2_TX8N")
		)
		(pad "2C9" thru_hole circle
			(at 16.999999 -6.899999 180)
			(size 0.6858 0.6858)
			(drill 0.381)
			(layers "*.Cu" "*.Mask")
			(remove_unused_layers no)
			(net "GND")
		)
		(pad "2D1" thru_hole circle
			(at 11.000001 -11.4 180)
			(size 0.6858 0.6858)
			(drill 0.381)
			(layers "*.Cu" "*.Mask")
			(remove_unused_layers no)
			(net "Net_379")
		)
		(pad "2D2" thru_hole circle
			(at 11.749999 -10 180)
			(size 0.6858 0.6858)
			(drill 0.381)
			(layers "*.Cu" "*.Mask")
			(remove_unused_layers no)
			(net "Net_378")
		)
		(pad "2D3" thru_hole circle
			(at 12.5 -10.699999 180)
			(size 0.6858 0.6858)
			(drill 0.381)
			(layers "*.Cu" "*.Mask")
			(remove_unused_layers no)
			(net "GND")
		)
		(pad "2D4" thru_hole circle
			(at 13.249999 -11.4 180)
			(size 0.6858 0.6858)
			(drill 0.381)
			(layers "*.Cu" "*.Mask")
			(remove_unused_layers no)
			(net "SAS_B2_TX5P")
		)
		(pad "2D5" thru_hole circle
			(at 14 -10 180)
			(size 0.6858 0.6858)
			(drill 0.381)
			(layers "*.Cu" "*.Mask")
			(remove_unused_layers no)
			(net "SAS_B2_TX5N")
		)
		(pad "2D6" thru_hole circle
			(at 14.750001 -10.699999 180)
			(size 0.6858 0.6858)
			(drill 0.381)
			(layers "*.Cu" "*.Mask")
			(remove_unused_layers no)
			(net "GND")
		)
		(pad "2D7" thru_hole circle
			(at 15.499999 -11.4 180)
			(size 0.6858 0.6858)
			(drill 0.381)
			(layers "*.Cu" "*.Mask")
			(remove_unused_layers no)
			(net "SAS_B2_TX7P")
		)
		(pad "2D8" thru_hole circle
			(at 16.250001 -10 180)
			(size 0.6858 0.6858)
			(drill 0.381)
			(layers "*.Cu" "*.Mask")
			(remove_unused_layers no)
			(net "SAS_B2_TX7N")
		)
		(pad "2D9" thru_hole circle
			(at 16.999999 -10.699999 180)
			(size 0.6858 0.6858)
			(drill 0.381)
			(layers "*.Cu" "*.Mask")
			(remove_unused_layers no)
			(net "GND")
		)
		(pad "3" thru_hole circle
			(at 12.5 -13.109999 180)
			(size 1.1176 1.1176)
			(drill 0.6096)
			(layers "*.Cu" "*.Mask")
			(remove_unused_layers no)
			(net "GND")
		)
		(pad "4" thru_hole circle
			(at 16.999999 -13.109999 180)
			(size 1.1176 1.1176)
			(drill 0.6096)
			(layers "*.Cu" "*.Mask")
			(remove_unused_layers no)
			(net "GND")
		)
		(pad "5" thru_hole circle
			(at -2.5 0.700001 180)
			(size 1.1176 1.1176)
			(drill 0.6096)
			(layers "*.Cu" "*.Mask")
			(remove_unused_layers no)
			(net "GND")
		)
		(pad "6" thru_hole circle
			(at 8.500001 0.700001 180)
			(size 1.1176 1.1176)
			(drill 0.6096)
			(layers "*.Cu" "*.Mask")
			(remove_unused_layers no)
			(net "GND")
		)
		(pad "7" thru_hole circle
			(at 19.499999 0.700001 180)
			(size 1.1176 1.1176)
			(drill 0.6096)
			(layers "*.Cu" "*.Mask")
			(remove_unused_layers no)
			(net "GND")
		)
		(pad "8" thru_hole circle
			(at -2.5 14.01 180)
			(size 1.1176 1.1176)
			(drill 0.6096)
			(layers "*.Cu" "*.Mask")
			(remove_unused_layers no)
			(net "GND")
		)
		(pad "9" thru_hole circle
			(at 8.500001 14.01 180)
			(size 1.1176 1.1176)
			(drill 0.6096)
			(layers "*.Cu" "*.Mask")
			(remove_unused_layers no)
			(net "GND")
		)
		(pad "10" thru_hole circle
			(at 19.499999 14.01 180)
			(size 1.1176 1.1176)
			(drill 0.6096)
			(layers "*.Cu" "*.Mask")
			(remove_unused_layers no)
			(net "GND")
		)
	)
)
